#ISCELL
  pure_quanta quanta_title_block_c *
  *
#CELL
  pure_quanta genoa_sp5 *
  page32_i13
#CELL
  pure_quanta genoa_sp5 *
  page32_i14
#CELL
  pure_quanta genoa_sp5 *
  page32_i15
#CELL
  pure_quanta genoa_sp5 *
  page32_i16
#ISCELL
  pure_quanta_power universal_gnd *
  page32_i17
#ISCELL
  pure_quanta_power universal_gnd *
  page32_i18
#ISCELL
  pure_quanta_power universal_gnd *
  page32_i19
#ISCELL
  pure_quanta_power universal_gnd *
  page32_i20
#ISCELL
  pure_quanta_power universal_gnd *
  page32_i21
#ISCELL
  pure_quanta_power universal_gnd *
  page32_i22
#ISCELL
  pure_quanta_power universal_gnd *
  page32_i23
#ISCELL
  pure_quanta_power universal_gnd *
  page32_i24
